(kicad_pcb
	(version 20241229)
	(generator "pcbnew")
	(generator_version "9.0")
	(general
		(thickness 1.711)
		(legacy_teardrops no)
	)
	(paper "A4")
	(title_block
		(title "Antmicro Baseboard for Jetson AGX Thor")
		(date "2026-02-18")
		(rev "1.1.0")
		(company "Antmicro Ltd")
		(comment 1 "www.antmicro.com")
		(comment 9 "footprints 925-928 of 1170")
	)
	(layers
		(0 "F.Cu" signal)
		(4 "In1.Cu" signal)
		(6 "In2.Cu" signal)
		(8 "In3.Cu" signal)
		(10 "In4.Cu" jumper)
		(12 "In5.Cu" signal)
		(14 "In6.Cu" signal)
		(16 "In7.Cu" signal)
		(18 "In8.Cu" signal)
		(2 "B.Cu" signal)
		(9 "F.Adhes" user "F.Adhesive")
		(11 "B.Adhes" user "B.Adhesive")
		(13 "F.Paste" user)
		(15 "B.Paste" user)
		(5 "F.SilkS" user "F.Silkscreen")
		(7 "B.SilkS" user "B.Silkscreen")
		(1 "F.Mask" user)
		(3 "B.Mask" user)
		(17 "Dwgs.User" user "User.Drawings")
		(19 "Cmts.User" user "User.Comments")
		(21 "Eco1.User" user "User.Eco1")
		(23 "Eco2.User" user "User.Eco2")
		(25 "Edge.Cuts" user)
		(27 "Margin" user)
		(31 "F.CrtYd" user "F.Courtyard")
		(29 "B.CrtYd" user "B.Courtyard")
		(35 "F.Fab" user)
		(33 "B.Fab" user)
	)
	(footprint "antmicro-footprints:R_0402_1005Metric"
		(layer "B.Cu")
		(at 200.3 130.5 90)
		(descr "Resistor SMD 0402")
		(tags "resistor SMD 0402")
		(property "Reference" "R62"
			(at -3.1 -0.3 90)
			(layer "B.SilkS")
			(effects
				(font
					(size 0.7 0.7)
					(thickness 0.15)
				)
				(justify right top mirror)
			)
		)
		(property "Value" "R_0R_0402"
			(at -1.011843 -1.772047 90)
			(layer "B.Fab")
			(effects
				(font
					(size 0.7 0.7)
					(thickness 0.15)
				)
				(justify right top mirror)
			)
		)
		(property "Datasheet" "https://industrial.panasonic.com/cdbs/www-data/pdf/RDA0000/AOA0000C301.pdf"
			(at 0 0 90)
			(layer "B.Fab")
			(hide yes)
			(effects
				(font
					(size 1.27 1.27)
					(thickness 0.15)
				)
				(justify mirror)
			)
		)
		(property "Description" "SMD Chip Resistor, Jumper, 0 ohm, 100 mW, 0402 [1005 Metric], Thick Film, General Purpose"
			(at 0 0 90)
			(layer "B.Fab")
			(hide yes)
			(effects
				(font
					(size 1.27 1.27)
					(thickness 0.15)
				)
				(justify mirror)
			)
		)
		(property "Manufacturer" "Panasonic"
			(at 0 0 270)
			(unlocked yes)
			(layer "B.Fab")
			(hide yes)
			(effects
				(font
					(size 1 1)
					(thickness 0.15)
				)
				(justify mirror)
			)
		)
		(property "MPN" "ERJ2GE0R00X"
			(at 0 0 270)
			(unlocked yes)
			(layer "B.Fab")
			(hide yes)
			(effects
				(font
					(size 1 1)
					(thickness 0.15)
				)
				(justify mirror)
			)
		)
		(property "Val" "0R"
			(at 0 0 270)
			(unlocked yes)
			(layer "B.Fab")
			(hide yes)
			(effects
				(font
					(size 1 1)
					(thickness 0.15)
				)
				(justify mirror)
			)
		)
		(property "License" "Apache-2.0"
			(at 0 0 270)
			(unlocked yes)
			(layer "B.Fab")
			(hide yes)
			(effects
				(font
					(size 1 1)
					(thickness 0.15)
				)
				(justify mirror)
			)
		)
		(property "Author" "Antmicro"
			(at 0 0 270)
			(unlocked yes)
			(layer "B.Fab")
			(hide yes)
			(effects
				(font
					(size 1 1)
					(thickness 0.15)
				)
				(justify mirror)
			)
		)
		(property "Tolerance" "~"
			(at 0 0 270)
			(unlocked yes)
			(layer "B.Fab")
			(hide yes)
			(effects
				(font
					(size 1 1)
					(thickness 0.15)
				)
				(justify mirror)
			)
		)
		(property "Current" "1A"
			(at 0 0 270)
			(unlocked yes)
			(layer "B.Fab")
			(hide yes)
			(effects
				(font
					(size 1 1)
					(thickness 0.15)
				)
				(justify mirror)
			)
		)
		(sheetname "/USB Hub/")
		(sheetfile "usb_hub.kicad_sch")
		(attr smd)
		(fp_rect
			(start -0.925 0.47)
			(end 0.925 -0.47)
			(stroke
				(width 0.05)
				(type default)
			)
			(fill no)
			(layer "B.CrtYd")
		)
		(fp_rect
			(start -0.5 0.25)
			(end 0.5 -0.25)
			(stroke
				(width 0.15)
				(type solid)
			)
			(fill no)
			(layer "B.Fab")
		)
		(fp_text user "${REFERENCE}"
			(at -0.95 -3.168 90)
			(layer "B.Fab")
			(effects
				(font
					(size 0.7 0.7)
					(thickness 0.15)
				)
				(justify right top mirror)
			)
		)
		(fp_text user "Author: Antmicro"
			(at -0.95 -4.169 90)
			(layer "B.Fab")
			(effects
				(font
					(size 0.7 0.7)
					(thickness 0.15)
				)
				(justify right top mirror)
			)
		)
		(fp_text user "License: Apache-2.0"
			(at -0.95 -5.169 90)
			(layer "B.Fab")
			(effects
				(font
					(size 0.7 0.7)
					(thickness 0.15)
				)
				(justify right top mirror)
			)
		)
		(pad "1" smd roundrect
			(at -0.48 0 90)
			(size 0.59 0.64)
			(layers "B.Cu" "B.Mask" "B.Paste")
			(roundrect_rratio 0.25)
			(net 1163 "Net-(U21-USB3DN_RXDM3)")
			(pintype "passive")
		)
		(pad "2" smd roundrect
			(at 0.48 0 90)
			(size 0.59 0.64)
			(layers "B.Cu" "B.Mask" "B.Paste")
			(roundrect_rratio 0.25)
			(net 1 "GND")
			(pintype "passive")
		)
	)
	(footprint "antmicro-footprints:C_0805_2012Metric"
		(layer "B.Cu")
		(at 73 141.75 90)
		(descr "Capacitor SMD 0805")
		(tags "capacitor SMD 0805")
		(property "Reference" "C227"
			(at -2.10551 1.198678 90)
			(layer "B.SilkS")
			(effects
				(font
					(size 0.7 0.7)
					(thickness 0.15)
				)
				(justify right top mirror)
			)
		)
		(property "Value" "C_22u_25V_0805"
			(at -2.055717 -1.963153 90)
			(layer "B.Fab")
			(effects
				(font
					(size 0.7 0.7)
					(thickness 0.15)
				)
				(justify right top mirror)
			)
		)
		(property "Datasheet" "https://product.samsungsem.com/mlcc/CL21A226MAYNNN.do"
			(at 0 0 90)
			(layer "B.Fab")
			(hide yes)
			(effects
				(font
					(size 1.27 1.27)
					(thickness 0.15)
				)
				(justify mirror)
			)
		)
		(property "Description" "SMT Multilayer Ceramic Capacitor, 22uF, +/-20%, 25V, X5R, 0805 [2012 Metric]"
			(at 0 0 90)
			(layer "B.Fab")
			(hide yes)
			(effects
				(font
					(size 1.27 1.27)
					(thickness 0.15)
				)
				(justify mirror)
			)
		)
		(property "MPN" "CL21A226MAYNNNE"
			(at 0 0 270)
			(unlocked yes)
			(layer "B.Fab")
			(hide yes)
			(effects
				(font
					(size 1 1)
					(thickness 0.15)
				)
				(justify mirror)
			)
		)
		(property "Val" "22u"
			(at 0 0 270)
			(unlocked yes)
			(layer "B.Fab")
			(hide yes)
			(effects
				(font
					(size 1 1)
					(thickness 0.15)
				)
				(justify mirror)
			)
		)
		(property "Voltage" "25V"
			(at 0 0 270)
			(unlocked yes)
			(layer "B.Fab")
			(hide yes)
			(effects
				(font
					(size 1 1)
					(thickness 0.15)
				)
				(justify mirror)
			)
		)
		(property "Dielectric" "X5R"
			(at 0 0 270)
			(unlocked yes)
			(layer "B.Fab")
			(hide yes)
			(effects
				(font
					(size 1 1)
					(thickness 0.15)
				)
				(justify mirror)
			)
		)
		(property "Manufacturer" "Samsung Electro-Mechanics"
			(at 0 0 270)
			(unlocked yes)
			(layer "B.Fab")
			(hide yes)
			(effects
				(font
					(size 1 1)
					(thickness 0.15)
				)
				(justify mirror)
			)
		)
		(property "License" "Apache-2.0"
			(at 0 0 270)
			(unlocked yes)
			(layer "B.Fab")
			(hide yes)
			(effects
				(font
					(size 1 1)
					(thickness 0.15)
				)
				(justify mirror)
			)
		)
		(property "Author" "Antmicro"
			(at 0 0 270)
			(unlocked yes)
			(layer "B.Fab")
			(hide yes)
			(effects
				(font
					(size 1 1)
					(thickness 0.15)
				)
				(justify mirror)
			)
		)
		(property "Public" "False"
			(at 0 0 270)
			(unlocked yes)
			(layer "B.Fab")
			(hide yes)
			(effects
				(font
					(size 1 1)
					(thickness 0.15)
				)
				(justify mirror)
			)
		)
		(sheetname "/Expansion connector/")
		(sheetfile "expansion_connector.kicad_sch")
		(attr smd)
		(fp_line
			(start -0.3 -0.7)
			(end 0.3 -0.7)
			(stroke
				(width 0.15)
				(type solid)
			)
			(layer "B.SilkS")
		)
		(fp_line
			(start -0.3 0.7)
			(end 0.3 0.7)
			(stroke
				(width 0.15)
				(type solid)
			)
			(layer "B.SilkS")
		)
		(fp_poly
			(pts
				(xy 1.95 0.9) (xy 1.95 -0.9) (xy -1.95 -0.9) (xy -1.95 0.9)
			)
			(stroke
				(width 0.05)
				(type default)
			)
			(fill no)
			(layer "B.CrtYd")
		)
		(fp_poly
			(pts
				(xy -0.95 0.675001) (xy -0.95 -0.675001) (xy 0.95 -0.675001) (xy 0.95 0.675001)
			)
			(stroke
				(width 0.15)
				(type solid)
			)
			(fill no)
			(layer "B.Fab")
		)
		(fp_text user "License: Apache-2.0"
			(at -1.9 -4.947 90)
			(layer "B.Fab")
			(effects
				(font
					(size 0.7 0.7)
					(thickness 0.15)
				)
				(justify right top mirror)
			)
		)
		(fp_text user "Author: Antmicro"
			(at -1.9 -5.947 90)
			(layer "B.Fab")
			(effects
				(font
					(size 0.7 0.7)
					(thickness 0.15)
				)
				(justify right top mirror)
			)
		)
		(fp_text user "${REFERENCE}"
			(at -1.899999 -3.947 90)
			(layer "B.Fab")
			(effects
				(font
					(size 0.7 0.7)
					(thickness 0.15)
				)
				(justify right top mirror)
			)
		)
		(pad "1" smd roundrect
			(at -1.099999 0 90)
			(size 1.2 1.3)
			(layers "B.Cu" "B.Mask" "B.Paste")
			(roundrect_rratio 0.25)
			(net 1 "GND")
			(pintype "passive")
		)
		(pad "2" smd roundrect
			(at 1.099999 0 90)
			(size 1.2 1.3)
			(layers "B.Cu" "B.Mask" "B.Paste")
			(roundrect_rratio 0.25)
			(net 289 "/Expansion connector/+12V_FMC")
			(pintype "passive")
		)
	)
	(footprint "antmicro-footprints:TSOT23-6"
		(layer "B.Cu")
		(at 143.6 62.08 -90)
		(property "Reference" "U55"
			(at -0.18 -2.6 90)
			(layer "B.SilkS")
			(effects
				(font
					(size 0.7 0.7)
					(thickness 0.15)
				)
				(justify left bottom mirror)
			)
		)
		(property "Value" "AP22615A_TSOT26"
			(at 0 -2.6 90)
			(layer "B.Fab")
			(effects
				(font
					(size 0.7 0.7)
					(thickness 0.15)
				)
				(justify left bottom mirror)
			)
		)
		(property "Datasheet" "https://www.mouser.com/datasheet/2/115/DIOD_S_A0008958405_1-2543193.pdf"
			(at 0 0 90)
			(layer "B.Fab")
			(hide yes)
			(effects
				(font
					(size 1.27 1.27)
					(thickness 0.15)
				)
				(justify mirror)
			)
		)
		(property "Description" "Power Load Distribution Switch, High Side, Active High, 1 Output, 5.5 V, 3.6 A, 0.04 ohm, TSOT-26-6"
			(at 0 0 90)
			(layer "B.Fab")
			(hide yes)
			(effects
				(font
					(size 1.27 1.27)
					(thickness 0.15)
				)
				(justify mirror)
			)
		)
		(property "MPN" "AP22615AWU-7"
			(at 0 0 270)
			(unlocked yes)
			(layer "B.Fab")
			(hide yes)
			(effects
				(font
					(size 1 1)
					(thickness 0.15)
				)
				(justify mirror)
			)
		)
		(property "Manufacturer" "Diodes Incorporated"
			(at 0 0 270)
			(unlocked yes)
			(layer "B.Fab")
			(hide yes)
			(effects
				(font
					(size 1 1)
					(thickness 0.15)
				)
				(justify mirror)
			)
		)
		(property "Author" "Antmicro"
			(at 0 0 270)
			(unlocked yes)
			(layer "B.Fab")
			(hide yes)
			(effects
				(font
					(size 1 1)
					(thickness 0.15)
				)
				(justify mirror)
			)
		)
		(property "License" "Apache-2.0"
			(at 0 0 270)
			(unlocked yes)
			(layer "B.Fab")
			(hide yes)
			(effects
				(font
					(size 1 1)
					(thickness 0.15)
				)
				(justify mirror)
			)
		)
		(sheetname "/Peripherals/")
		(sheetfile "peripherals.kicad_sch")
		(attr smd)
		(fp_line
			(start -1 1.5)
			(end -1 1.375)
			(stroke
				(width 0.15)
				(type solid)
			)
			(layer "B.SilkS")
		)
		(fp_line
			(start 1 1.497)
			(end -1 1.5)
			(stroke
				(width 0.15)
				(type solid)
			)
			(layer "B.SilkS")
		)
		(fp_line
			(start 1 1.497)
			(end 1 1.375)
			(stroke
				(width 0.15)
				(type solid)
			)
			(layer "B.SilkS")
		)
		(fp_line
			(start -1 -1.55)
			(end -1 -1.4)
			(stroke
				(width 0.15)
				(type solid)
			)
			(layer "B.SilkS")
		)
		(fp_line
			(start 1 -1.55)
			(end 1 -1.4)
			(stroke
				(width 0.15)
				(type solid)
			)
			(layer "B.SilkS")
		)
		(fp_line
			(start 1 -1.55)
			(end -1 -1.55)
			(stroke
				(width 0.15)
				(type solid)
			)
			(layer "B.SilkS")
		)
		(fp_circle
			(center -1.44 1.5)
			(end -1.39 1.5)
			(stroke
				(width 0.15)
				(type solid)
			)
			(fill yes)
			(layer "B.SilkS")
		)
		(fp_rect
			(start 1.93 1.7)
			(end -1.93 -1.7)
			(stroke
				(width 0.05)
				(type solid)
			)
			(fill no)
			(layer "B.CrtYd")
		)
		(fp_line
			(start -0.45 1.521)
			(end -0.876 1.096)
			(stroke
				(width 0.15)
				(type solid)
			)
			(layer "B.Fab")
		)
		(fp_rect
			(start 0.875 -1.528)
			(end -0.875 1.525)
			(stroke
				(width 0.15)
				(type solid)
			)
			(fill no)
			(layer "B.Fab")
		)
		(fp_text user "License: Apache-2.0"
			(at -1.93 -6.199 90)
			(layer "B.Fab")
			(effects
				(font
					(size 0.7 0.7)
					(thickness 0.15)
				)
				(justify left bottom mirror)
			)
		)
		(fp_text user "${REFERENCE}"
			(at -1.93 -3.8 90)
			(layer "B.Fab")
			(effects
				(font
					(size 0.7 0.7)
					(thickness 0.15)
				)
				(justify left bottom mirror)
			)
		)
		(fp_text user "Author: Antmicro"
			(at -1.93 -5 90)
			(layer "B.Fab")
			(effects
				(font
					(size 0.7 0.7)
					(thickness 0.15)
				)
				(justify left bottom mirror)
			)
		)
		(pad "1" smd rect
			(at -1.301 0.947)
			(size 0.7 1.2)
			(layers "B.Cu" "B.Mask" "B.Paste")
			(net 839 "/Peripherals/I2C_CONN2_3V3")
			(pinfunction "OUT")
			(pintype "power_out")
		)
		(pad "2" smd rect
			(at -1.301 -0.004)
			(size 0.7 1.2)
			(layers "B.Cu" "B.Mask" "B.Paste")
			(net 1 "GND")
			(pinfunction "GND")
			(pintype "power_in")
		)
		(pad "3" smd rect
			(at -1.301 -0.954)
			(size 0.7 1.2)
			(layers "B.Cu" "B.Mask" "B.Paste")
			(net 1122 "unconnected-(U55-FLG-Pad3)")
			(pinfunction "FLG")
			(pintype "output+no_connect")
		)
		(pad "4" smd rect
			(at 1.299 -0.954)
			(size 0.7 1.2)
			(layers "B.Cu" "B.Mask" "B.Paste")
			(net 90 "/Peripherals/I2C_CONN_PEN")
			(pinfunction "EN")
			(pintype "input")
		)
		(pad "5" smd rect
			(at 1.299 -0.004)
			(size 0.7 1.2)
			(layers "B.Cu" "B.Mask" "B.Paste")
			(net 1010 "Net-(U55-ISET)")
			(pinfunction "ISET")
			(pintype "passive")
		)
		(pad "6" smd rect
			(at 1.299 0.947)
			(size 0.7 1.2)
			(layers "B.Cu" "B.Mask" "B.Paste")
			(net 2 "+3V3")
			(pinfunction "IN")
			(pintype "power_in")
		)
	)
	(footprint "antmicro-footprints:C_0603_1608Metric_EIA"
		(layer "B.Cu")
		(at 124.6 137.6 180)
		(descr "Capacitor SMD 0603, IPC-7351 Density Level A")
		(tags "Capacitor 0603")
		(property "Reference" "C170"
			(at -4.6 -0.4 0)
			(layer "B.SilkS")
			(effects
				(font
					(size 0.7 0.7)
					(thickness 0.15)
				)
				(justify left bottom mirror)
			)
		)
		(property "Value" "C_22u_16V_0603"
			(at -1.42757 -1.770288 0)
			(layer "B.Fab")
			(effects
				(font
					(size 0.7 0.7)
					(thickness 0.15)
				)
				(justify left bottom mirror)
			)
		)
		(property "Datasheet" "https://product.samsungsem.com/mlcc/CL10A226MO7JZN.do"
			(at 0 0 0)
			(layer "B.Fab")
			(hide yes)
			(effects
				(font
					(size 1.27 1.27)
					(thickness 0.15)
				)
				(justify mirror)
			)
		)
		(property "Description" "SMD Multilayer Ceramic Capacitor"
			(at 0 0 0)
			(layer "B.Fab")
			(hide yes)
			(effects
				(font
					(size 1.27 1.27)
					(thickness 0.15)
				)
				(justify mirror)
			)
		)
		(property "MPN" "CL10A226MO7JZNC"
			(at 0 0 180)
			(unlocked yes)
			(layer "B.Fab")
			(hide yes)
			(effects
				(font
					(size 1 1)
					(thickness 0.15)
				)
				(justify mirror)
			)
		)
		(property "Manufacturer" "Samsung Electro-Mechanics"
			(at 0 0 180)
			(unlocked yes)
			(layer "B.Fab")
			(hide yes)
			(effects
				(font
					(size 1 1)
					(thickness 0.15)
				)
				(justify mirror)
			)
		)
		(property "License" "Apache-2.0"
			(at 0 0 180)
			(unlocked yes)
			(layer "B.Fab")
			(hide yes)
			(effects
				(font
					(size 1 1)
					(thickness 0.15)
				)
				(justify mirror)
			)
		)
		(property "Author" "Antmicro"
			(at 0 0 180)
			(unlocked yes)
			(layer "B.Fab")
			(hide yes)
			(effects
				(font
					(size 1 1)
					(thickness 0.15)
				)
				(justify mirror)
			)
		)
		(property "Val" "22u"
			(at 0 0 180)
			(unlocked yes)
			(layer "B.Fab")
			(hide yes)
			(effects
				(font
					(size 1 1)
					(thickness 0.15)
				)
				(justify mirror)
			)
		)
		(property "Voltage" "16V"
			(at 0 0 180)
			(unlocked yes)
			(layer "B.Fab")
			(hide yes)
			(effects
				(font
					(size 1 1)
					(thickness 0.15)
				)
				(justify mirror)
			)
		)
		(property "Dielectric" ""
			(at 0 0 180)
			(unlocked yes)
			(layer "B.Fab")
			(hide yes)
			(effects
				(font
					(size 1 1)
					(thickness 0.15)
				)
				(justify mirror)
			)
		)
		(sheetname "/M.2/")
		(sheetfile "m2.kicad_sch")
		(attr smd)
		(fp_line
			(start -0.15 0.55)
			(end 0.15 0.55)
			(stroke
				(width 0.15)
				(type solid)
			)
			(layer "B.SilkS")
		)
		(fp_line
			(start -0.15 -0.55)
			(end 0.15 -0.55)
			(stroke
				(width 0.15)
				(type solid)
			)
			(layer "B.SilkS")
		)
		(fp_rect
			(start -1.25 0.65)
			(end 1.25 -0.65)
			(stroke
				(width 0.05)
				(type solid)
			)
			(fill no)
			(layer "B.CrtYd")
		)
		(fp_rect
			(start -0.8 0.45)
			(end 0.8 -0.45)
			(stroke
				(width 0.15)
				(type solid)
			)
			(fill no)
			(layer "B.Fab")
		)
		(fp_text user "${REFERENCE}"
			(at -1.682 -3.895 0)
			(layer "B.Fab")
			(effects
				(font
					(size 0.7 0.7)
					(thickness 0.15)
				)
				(justify left bottom mirror)
			)
		)
		(fp_text user "License: Apache-2.0"
			(at -1.682 -5.895 0)
			(layer "B.Fab")
			(effects
				(font
					(size 0.7 0.7)
					(thickness 0.15)
				)
				(justify left bottom mirror)
			)
		)
		(fp_text user "Author: Antmicro"
			(at -1.682 -4.894 0)
			(layer "B.Fab")
			(effects
				(font
					(size 0.7 0.7)
					(thickness 0.15)
				)
				(justify left bottom mirror)
			)
		)
		(pad "1" smd roundrect
			(at -0.7 0 180)
			(size 0.8 1.1)
			(layers "B.Cu" "B.Mask" "B.Paste")
			(roundrect_rratio 0.2)
			(net 1 "GND")
			(pintype "passive")
		)
		(pad "2" smd roundrect
			(at 0.7 0 180)
			(size 0.8 1.1)
			(layers "B.Cu" "B.Mask" "B.Paste")
			(roundrect_rratio 0.2)
			(net 2 "+3V3")
			(pintype "passive")
		)
	)
)
